# T6G (Grand Teton) — schematic netlist excerpt (pin names and nets, part order shuffled) for the footprints in the layout excerpt that follows; sources: Cadence DE-HDL packaged netlist, KiCad conversion of 04192023_DAF0TMB3IC0_F0TG_MB_C_brd_V02_OCP.brd

PR2535  Q_RES  10 1% CHIP  pkg 0402LF  page 266 : A = P12V_HSC_GATE_G5 ; B = P12V_HSC_GATE2
R1353  Q_RES  0 5% CHIP  pkg 0402LF  page 172 : A = HDT_HDR_R_TMS ; B = HDT_HDR_TMS
R995  Q_RES  4.7K 5% CHIP  pkg 0201LF  page 276 : A = TEST2_RT_CPU0_P0 ; B = GND

(kicad_pcb
	(version 20260206)
	(generator "pcbnew")
	(generator_version "10.0")
	(general
		(thickness 1.6)
		(legacy_teardrops no)
	)
	(paper "A4")
	(title_block
		(title "04192023_DAF0TMB3IC0_F0TG_MB_C_brd_V02_OCP.brd")
		(comment 1 "Grand Teton / footprints 4389-4391 of 8354")
	)
	(layers
		(0 "F.Cu" signal "TOP")
		(4 "In1.Cu" signal "GND")
		(6 "In2.Cu" signal "IN1")
		(8 "In3.Cu" signal "GND1")
		(10 "In4.Cu" signal "IN2")
		(12 "In5.Cu" signal "GND2")
		(14 "In6.Cu" signal "IN3")
		(16 "In7.Cu" signal "GND3")
		(18 "In8.Cu" signal "VCC")
		(20 "In9.Cu" signal "VCC1")
		(22 "In10.Cu" signal "GND4")
		(24 "In11.Cu" signal "IN4")
		(26 "In12.Cu" signal "GND5")
		(28 "In13.Cu" signal "IN5")
		(30 "In14.Cu" signal "GND6")
		(32 "In15.Cu" signal "IN6")
		(34 "In16.Cu" signal "GND7")
		(2 "B.Cu" signal "BOTTOM")
		(9 "F.Adhes" user "F.Adhesive")
		(11 "B.Adhes" user "B.Adhesive")
		(13 "F.Paste" user "Package Geometry/Pastemask Top")
		(15 "B.Paste" user "Package Geometry/Pastemask Bottom")
		(5 "F.SilkS" user "Ref Des/Silkscreen Top")
		(7 "B.SilkS" user "Ref Des/Silkscreen Bottom")
		(1 "F.Mask" user "Board Geometry/Soldermask Top")
		(3 "B.Mask" user "Board Geometry/Soldermask Bottom")
		(17 "Dwgs.User" user "User.Drawings")
		(19 "Cmts.User" user "User.Comments")
		(21 "Eco1.User" user "User.Eco1")
		(23 "Eco2.User" user "User.Eco2")
		(25 "Edge.Cuts" user "Board Geometry/Outline")
		(27 "Margin" user)
		(31 "F.CrtYd" user "Package Geometry/Place Bound Top")
		(29 "B.CrtYd" user "Package Geometry/Place Bound Bottom")
		(35 "F.Fab" user "Ref Des/Assembly Top")
		(33 "B.Fab" user "Ref Des/Assembly Bottom")
	)
	(footprint ""
		(layer "F.Cu")
		(at 386.211826 -54.1655 180)
		(property "Reference" "R1353"
			(at 0 0 180)
			(layer "F.SilkS")
			(hide yes)
			(effects
				(font
					(size 1.27 1.27)
				)
			)
		)
		(property "Value" ""
			(at 0 0 180)
			(layer "F.Fab")
			(effects
				(font
					(size 1.27 1.27)
				)
			)
		)
		(duplicate_pad_numbers_are_jumpers no)
		(fp_line
			(start 0.7874 0.4064)
			(end -0.7874 0.4064)
			(stroke
				(width 0.1524)
				(type default)
			)
			(layer "F.SilkS")
		)
		(fp_line
			(start 0.7874 -0.4064)
			(end 0.7874 0.4064)
			(stroke
				(width 0.1524)
				(type default)
			)
			(layer "F.SilkS")
		)
		(fp_line
			(start -0.7874 0.4064)
			(end -0.7874 -0.4064)
			(stroke
				(width 0.1524)
				(type default)
			)
			(layer "F.SilkS")
		)
		(fp_line
			(start -0.7874 -0.4064)
			(end 0.7874 -0.4064)
			(stroke
				(width 0.1524)
				(type default)
			)
			(layer "F.SilkS")
		)
		(fp_line
			(start 0.67945 0.3048)
			(end 0.120396 0.3048)
			(stroke
				(width 0.1)
				(type default)
			)
			(layer "F.Fab")
		)
		(fp_line
			(start 0.67945 -0.3048)
			(end 0.67945 0.3048)
			(stroke
				(width 0.1)
				(type default)
			)
			(layer "F.Fab")
		)
		(fp_line
			(start 0.12065 -0.2794)
			(end 0.12065 -0.3048)
			(stroke
				(width 0.1)
				(type default)
			)
			(layer "F.Fab")
		)
		(fp_line
			(start 0.12065 -0.3048)
			(end 0.67945 -0.3048)
			(stroke
				(width 0.1)
				(type default)
			)
			(layer "F.Fab")
		)
		(fp_line
			(start 0.120396 0.3048)
			(end 0.120396 0.2794)
			(stroke
				(width 0.1)
				(type default)
			)
			(layer "F.Fab")
		)
		(fp_line
			(start 0.120396 0.2794)
			(end -0.12065 0.2794)
			(stroke
				(width 0.1)
				(type default)
			)
			(layer "F.Fab")
		)
		(fp_line
			(start -0.12065 0.3048)
			(end -0.67945 0.3048)
			(stroke
				(width 0.1)
				(type default)
			)
			(layer "F.Fab")
		)
		(fp_line
			(start -0.12065 0.2794)
			(end -0.12065 0.3048)
			(stroke
				(width 0.1)
				(type default)
			)
			(layer "F.Fab")
		)
		(fp_line
			(start -0.12065 -0.2794)
			(end 0.12065 -0.2794)
			(stroke
				(width 0.1)
				(type default)
			)
			(layer "F.Fab")
		)
		(fp_line
			(start -0.12065 -0.305054)
			(end -0.12065 -0.2794)
			(stroke
				(width 0.1)
				(type default)
			)
			(layer "F.Fab")
		)
		(fp_line
			(start -0.67945 0.3048)
			(end -0.67945 -0.305054)
			(stroke
				(width 0.1)
				(type default)
			)
			(layer "F.Fab")
		)
		(fp_line
			(start -0.67945 -0.305054)
			(end -0.12065 -0.305054)
			(stroke
				(width 0.1)
				(type default)
			)
			(layer "F.Fab")
		)
		(pad "1" smd circle
			(at -0.40005 0 180)
			(size 0 0)
			(layers "F.Cu" "F.Mask" "F.Paste")
			(net "HDT_HDR_R_TMS")
		)
		(pad "2" smd circle
			(at 0.40005 0 180)
			(size 0 0)
			(layers "F.Cu" "F.Mask" "F.Paste")
			(net "HDT_HDR_TMS")
		)
	)
	(footprint ""
		(layer "F.Cu")
		(at 243.961158 -380.66853)
		(property "Reference" "PR2535"
			(at 0 0 0)
			(layer "F.SilkS")
			(hide yes)
			(effects
				(font
					(size 1.27 1.27)
				)
			)
		)
		(property "Value" ""
			(at 0 0 0)
			(layer "F.Fab")
			(effects
				(font
					(size 1.27 1.27)
				)
			)
		)
		(duplicate_pad_numbers_are_jumpers no)
		(fp_line
			(start -0.7874 -0.4064)
			(end 0.7874 -0.4064)
			(stroke
				(width 0.1524)
				(type default)
			)
			(layer "F.SilkS")
		)
		(fp_line
			(start -0.7874 0.4064)
			(end -0.7874 -0.4064)
			(stroke
				(width 0.1524)
				(type default)
			)
			(layer "F.SilkS")
		)
		(fp_line
			(start 0.7874 -0.4064)
			(end 0.7874 0.4064)
			(stroke
				(width 0.1524)
				(type default)
			)
			(layer "F.SilkS")
		)
		(fp_line
			(start 0.7874 0.4064)
			(end -0.7874 0.4064)
			(stroke
				(width 0.1524)
				(type default)
			)
			(layer "F.SilkS")
		)
		(fp_line
			(start -0.67945 -0.305054)
			(end -0.12065 -0.305054)
			(stroke
				(width 0.1)
				(type default)
			)
			(layer "F.Fab")
		)
		(fp_line
			(start -0.67945 0.3048)
			(end -0.67945 -0.305054)
			(stroke
				(width 0.1)
				(type default)
			)
			(layer "F.Fab")
		)
		(fp_line
			(start -0.12065 -0.305054)
			(end -0.12065 -0.2794)
			(stroke
				(width 0.1)
				(type default)
			)
			(layer "F.Fab")
		)
		(fp_line
			(start -0.12065 -0.2794)
			(end 0.12065 -0.2794)
			(stroke
				(width 0.1)
				(type default)
			)
			(layer "F.Fab")
		)
		(fp_line
			(start -0.12065 0.2794)
			(end -0.12065 0.3048)
			(stroke
				(width 0.1)
				(type default)
			)
			(layer "F.Fab")
		)
		(fp_line
			(start -0.12065 0.3048)
			(end -0.67945 0.3048)
			(stroke
				(width 0.1)
				(type default)
			)
			(layer "F.Fab")
		)
		(fp_line
			(start 0.120396 0.2794)
			(end -0.12065 0.2794)
			(stroke
				(width 0.1)
				(type default)
			)
			(layer "F.Fab")
		)
		(fp_line
			(start 0.120396 0.3048)
			(end 0.120396 0.2794)
			(stroke
				(width 0.1)
				(type default)
			)
			(layer "F.Fab")
		)
		(fp_line
			(start 0.12065 -0.3048)
			(end 0.67945 -0.3048)
			(stroke
				(width 0.1)
				(type default)
			)
			(layer "F.Fab")
		)
		(fp_line
			(start 0.12065 -0.2794)
			(end 0.12065 -0.3048)
			(stroke
				(width 0.1)
				(type default)
			)
			(layer "F.Fab")
		)
		(fp_line
			(start 0.67945 -0.3048)
			(end 0.67945 0.3048)
			(stroke
				(width 0.1)
				(type default)
			)
			(layer "F.Fab")
		)
		(fp_line
			(start 0.67945 0.3048)
			(end 0.120396 0.3048)
			(stroke
				(width 0.1)
				(type default)
			)
			(layer "F.Fab")
		)
		(pad "1" smd circle
			(at -0.40005 0)
			(size 0 0)
			(layers "F.Cu" "F.Mask" "F.Paste")
			(net "P12V_HSC_GATE_G5")
		)
		(pad "2" smd circle
			(at 0.40005 0)
			(size 0 0)
			(layers "F.Cu" "F.Mask" "F.Paste")
			(net "P12V_HSC_GATE2")
		)
	)
	(footprint ""
		(layer "F.Cu")
		(at 299.265594 -392.1252)
		(property "Reference" "R995"
			(at 0 0 0)
			(layer "F.SilkS")
			(hide yes)
			(effects
				(font
					(size 1.27 1.27)
				)
			)
		)
		(property "Value" ""
			(at 0 0 0)
			(layer "F.Fab")
			(effects
				(font
					(size 1.27 1.27)
				)
			)
		)
		(duplicate_pad_numbers_are_jumpers no)
		(fp_line
			(start -0.32512 -0.175006)
			(end 0.32512 -0.175006)
			(stroke
				(width 0.1)
				(type default)
			)
			(layer "F.Fab")
		)
		(fp_line
			(start -0.32512 0.175006)
			(end -0.32512 -0.175006)
			(stroke
				(width 0.1)
				(type default)
			)
			(layer "F.Fab")
		)
		(fp_line
			(start 0.32512 -0.175006)
			(end 0.32512 0.175006)
			(stroke
				(width 0.1)
				(type default)
			)
			(layer "F.Fab")
		)
		(fp_line
			(start 0.32512 0.175006)
			(end -0.32512 0.175006)
			(stroke
				(width 0.1)
				(type default)
			)
			(layer "F.Fab")
		)
		(pad "1" smd rect
			(at -0.2667 0)
			(size 0.3048 0.381)
			(layers "F.Cu" "F.Mask" "F.Paste")
			(net "TEST2_RT_CPU0_P0")
		)
		(pad "2" smd rect
			(at 0.2667 0 180)
			(size 0.3048 0.381)
			(layers "F.Cu" "F.Mask" "F.Paste")
			(net "GND")
		)
	)
)
